# S9S_MB_2U (Grand Teton) — schematic netlist excerpt (pin names and nets, part order shuffled) for the footprints in the layout excerpt that follows; sources: Cadence DE-HDL packaged netlist, KiCad conversion of 03242023_DA0F0TMBIJ0_F0T_Motherboard_J_brd_V01_OCP.brd

C1979  Q_CAP  0.1UF 25V 10% X7R  pkg 0402  page 150 : A = P3V3_AUX ; B = GND
C224  Q_CAP  10UF 6.3V 20% X6S  pkg C0402  page 77 : A = PVCCIN_CPU1 ; B = GND

(kicad_pcb
	(version 20260206)
	(generator "pcbnew")
	(generator_version "10.0")
	(general
		(thickness 1.6)
		(legacy_teardrops no)
	)
	(paper "A4")
	(title_block
		(title "03242023_DA0F0TMBIJ0_F0T_Motherboard_J_brd_V01_OCP.brd")
		(comment 1 "Grand Teton / footprints 2748-2749 of 6105")
	)
	(layers
		(0 "F.Cu" signal "TOP")
		(4 "In1.Cu" signal "GND")
		(6 "In2.Cu" signal "IN1")
		(8 "In3.Cu" signal "GND1")
		(10 "In4.Cu" signal "IN2")
		(12 "In5.Cu" signal "GND2")
		(14 "In6.Cu" signal "IN3")
		(16 "In7.Cu" signal "GND3")
		(18 "In8.Cu" signal "VCC")
		(20 "In9.Cu" signal "VCC1")
		(22 "In10.Cu" signal "GND4")
		(24 "In11.Cu" signal "IN4")
		(26 "In12.Cu" signal "GND5")
		(28 "In13.Cu" signal "IN5")
		(30 "In14.Cu" signal "GND6")
		(32 "In15.Cu" signal "IN6")
		(34 "In16.Cu" signal "GND7")
		(2 "B.Cu" signal "BOTTOM")
		(9 "F.Adhes" user "F.Adhesive")
		(11 "B.Adhes" user "B.Adhesive")
		(13 "F.Paste" user "Package Geometry/Pastemask Top")
		(15 "B.Paste" user "Package Geometry/Pastemask Bottom")
		(5 "F.SilkS" user "Ref Des/Silkscreen Top")
		(7 "B.SilkS" user "Ref Des/Silkscreen Bottom")
		(1 "F.Mask" user "Board Geometry/Soldermask Top")
		(3 "B.Mask" user "Board Geometry/Soldermask Bottom")
		(17 "Dwgs.User" user "User.Drawings")
		(19 "Cmts.User" user "User.Comments")
		(21 "Eco1.User" user "User.Eco1")
		(23 "Eco2.User" user "User.Eco2")
		(25 "Edge.Cuts" user "Board Geometry/Outline")
		(27 "Margin" user)
		(31 "F.CrtYd" user "Package Geometry/Place Bound Top")
		(29 "B.CrtYd" user "Package Geometry/Place Bound Bottom")
		(35 "F.Fab" user "Ref Des/Assembly Top")
		(33 "B.Fab" user "Ref Des/Assembly Bottom")
	)
	(footprint ""
		(layer "F.Cu")
		(at 118.542816 -244.032024 90)
		(property "Reference" "C224"
			(at 0 0 90)
			(layer "F.SilkS")
			(hide yes)
			(effects
				(font
					(size 1.27 1.27)
				)
			)
		)
		(property "Value" ""
			(at 0 0 90)
			(layer "F.Fab")
			(effects
				(font
					(size 1.27 1.27)
				)
			)
		)
		(duplicate_pad_numbers_are_jumpers no)
		(fp_line
			(start 0.7874 -0.4064)
			(end 0.7874 0.4064)
			(stroke
				(width 0.1524)
				(type default)
			)
			(layer "F.SilkS")
		)
		(fp_line
			(start -0.7874 -0.4064)
			(end 0.7874 -0.4064)
			(stroke
				(width 0.1524)
				(type default)
			)
			(layer "F.SilkS")
		)
		(fp_line
			(start 0.7874 0.4064)
			(end -0.7874 0.4064)
			(stroke
				(width 0.1524)
				(type default)
			)
			(layer "F.SilkS")
		)
		(fp_line
			(start -0.7874 0.4064)
			(end -0.7874 -0.4064)
			(stroke
				(width 0.1524)
				(type default)
			)
			(layer "F.SilkS")
		)
		(fp_line
			(start -0.12065 -0.305054)
			(end -0.12065 -0.2794)
			(stroke
				(width 0.1)
				(type default)
			)
			(layer "F.Fab")
		)
		(fp_line
			(start -0.67945 -0.305054)
			(end -0.12065 -0.305054)
			(stroke
				(width 0.1)
				(type default)
			)
			(layer "F.Fab")
		)
		(fp_line
			(start 0.67945 -0.3048)
			(end 0.67945 0.3048)
			(stroke
				(width 0.1)
				(type default)
			)
			(layer "F.Fab")
		)
		(fp_line
			(start 0.12065 -0.3048)
			(end 0.67945 -0.3048)
			(stroke
				(width 0.1)
				(type default)
			)
			(layer "F.Fab")
		)
		(fp_line
			(start 0.12065 -0.2794)
			(end 0.12065 -0.3048)
			(stroke
				(width 0.1)
				(type default)
			)
			(layer "F.Fab")
		)
		(fp_line
			(start -0.12065 -0.2794)
			(end 0.12065 -0.2794)
			(stroke
				(width 0.1)
				(type default)
			)
			(layer "F.Fab")
		)
		(fp_line
			(start 0.120396 0.2794)
			(end -0.12065 0.2794)
			(stroke
				(width 0.1)
				(type default)
			)
			(layer "F.Fab")
		)
		(fp_line
			(start -0.12065 0.2794)
			(end -0.12065 0.3048)
			(stroke
				(width 0.1)
				(type default)
			)
			(layer "F.Fab")
		)
		(fp_line
			(start 0.67945 0.3048)
			(end 0.120396 0.3048)
			(stroke
				(width 0.1)
				(type default)
			)
			(layer "F.Fab")
		)
		(fp_line
			(start 0.120396 0.3048)
			(end 0.120396 0.2794)
			(stroke
				(width 0.1)
				(type default)
			)
			(layer "F.Fab")
		)
		(fp_line
			(start -0.12065 0.3048)
			(end -0.67945 0.3048)
			(stroke
				(width 0.1)
				(type default)
			)
			(layer "F.Fab")
		)
		(fp_line
			(start -0.67945 0.3048)
			(end -0.67945 -0.305054)
			(stroke
				(width 0.1)
				(type default)
			)
			(layer "F.Fab")
		)
		(pad "1" smd circle
			(at -0.40005 0 90)
			(size 0 0)
			(layers "F.Cu" "F.Mask" "F.Paste")
			(net "PVCCIN_CPU1")
		)
		(pad "2" smd circle
			(at 0.40005 0 90)
			(size 0 0)
			(layers "F.Cu" "F.Mask" "F.Paste")
			(net "GND")
		)
	)
	(footprint ""
		(layer "F.Cu")
		(at 112.492282 -406.439116 180)
		(property "Reference" "C1979"
			(at 0 0 180)
			(layer "F.SilkS")
			(hide yes)
			(effects
				(font
					(size 1.27 1.27)
				)
			)
		)
		(property "Value" ""
			(at 0 0 180)
			(layer "F.Fab")
			(effects
				(font
					(size 1.27 1.27)
				)
			)
		)
		(duplicate_pad_numbers_are_jumpers no)
		(fp_line
			(start 0.7874 0.4064)
			(end -0.7874 0.4064)
			(stroke
				(width 0.1524)
				(type default)
			)
			(layer "F.SilkS")
		)
		(fp_line
			(start 0.7874 -0.4064)
			(end 0.7874 0.4064)
			(stroke
				(width 0.1524)
				(type default)
			)
			(layer "F.SilkS")
		)
		(fp_line
			(start -0.7874 0.4064)
			(end -0.7874 -0.4064)
			(stroke
				(width 0.1524)
				(type default)
			)
			(layer "F.SilkS")
		)
		(fp_line
			(start -0.7874 -0.4064)
			(end 0.7874 -0.4064)
			(stroke
				(width 0.1524)
				(type default)
			)
			(layer "F.SilkS")
		)
		(fp_line
			(start 0.67945 0.3048)
			(end 0.120396 0.3048)
			(stroke
				(width 0.1)
				(type default)
			)
			(layer "F.Fab")
		)
		(fp_line
			(start 0.67945 -0.3048)
			(end 0.67945 0.3048)
			(stroke
				(width 0.1)
				(type default)
			)
			(layer "F.Fab")
		)
		(fp_line
			(start 0.12065 -0.2794)
			(end 0.12065 -0.3048)
			(stroke
				(width 0.1)
				(type default)
			)
			(layer "F.Fab")
		)
		(fp_line
			(start 0.12065 -0.3048)
			(end 0.67945 -0.3048)
			(stroke
				(width 0.1)
				(type default)
			)
			(layer "F.Fab")
		)
		(fp_line
			(start 0.120396 0.3048)
			(end 0.120396 0.2794)
			(stroke
				(width 0.1)
				(type default)
			)
			(layer "F.Fab")
		)
		(fp_line
			(start 0.120396 0.2794)
			(end -0.12065 0.2794)
			(stroke
				(width 0.1)
				(type default)
			)
			(layer "F.Fab")
		)
		(fp_line
			(start -0.12065 0.3048)
			(end -0.67945 0.3048)
			(stroke
				(width 0.1)
				(type default)
			)
			(layer "F.Fab")
		)
		(fp_line
			(start -0.12065 0.2794)
			(end -0.12065 0.3048)
			(stroke
				(width 0.1)
				(type default)
			)
			(layer "F.Fab")
		)
		(fp_line
			(start -0.12065 -0.2794)
			(end 0.12065 -0.2794)
			(stroke
				(width 0.1)
				(type default)
			)
			(layer "F.Fab")
		)
		(fp_line
			(start -0.12065 -0.305054)
			(end -0.12065 -0.2794)
			(stroke
				(width 0.1)
				(type default)
			)
			(layer "F.Fab")
		)
		(fp_line
			(start -0.67945 0.3048)
			(end -0.67945 -0.305054)
			(stroke
				(width 0.1)
				(type default)
			)
			(layer "F.Fab")
		)
		(fp_line
			(start -0.67945 -0.305054)
			(end -0.12065 -0.305054)
			(stroke
				(width 0.1)
				(type default)
			)
			(layer "F.Fab")
		)
		(pad "1" smd circle
			(at -0.40005 0 180)
			(size 0 0)
			(layers "F.Cu" "F.Mask" "F.Paste")
			(net "P3V3_AUX")
		)
		(pad "2" smd circle
			(at 0.40005 0 180)
			(size 0 0)
			(layers "F.Cu" "F.Mask" "F.Paste")
			(net "GND")
		)
	)
)
